# S9S_MB_2U (Grand Teton) — schematic netlist excerpt (pin names and nets, part order shuffled) for the footprints in the layout excerpt that follows; sources: Cadence DE-HDL packaged netlist, KiCad conversion of 03242023_DA0F0TMBIJ0_F0T_Motherboard_J_brd_V01_OCP.brd

R2915  Q_RES  4.7K 5% CHIP  pkg 0402LF  page 151 : A = BMC_MONITER_R ; B = GND
R2835  Q_RES  4.7K 5% CHIP  pkg 0402LF  page 148 : A = P3V3_AUX ; B = BIC_MONITER_N

(kicad_pcb
	(version 20260206)
	(generator "pcbnew")
	(generator_version "10.0")
	(general
		(thickness 1.6)
		(legacy_teardrops no)
	)
	(paper "A4")
	(title_block
		(title "03242023_DA0F0TMBIJ0_F0T_Motherboard_J_brd_V01_OCP.brd")
		(comment 1 "Grand Teton / footprints 4094-4095 of 6105")
	)
	(layers
		(0 "F.Cu" signal "TOP")
		(4 "In1.Cu" signal "GND")
		(6 "In2.Cu" signal "IN1")
		(8 "In3.Cu" signal "GND1")
		(10 "In4.Cu" signal "IN2")
		(12 "In5.Cu" signal "GND2")
		(14 "In6.Cu" signal "IN3")
		(16 "In7.Cu" signal "GND3")
		(18 "In8.Cu" signal "VCC")
		(20 "In9.Cu" signal "VCC1")
		(22 "In10.Cu" signal "GND4")
		(24 "In11.Cu" signal "IN4")
		(26 "In12.Cu" signal "GND5")
		(28 "In13.Cu" signal "IN5")
		(30 "In14.Cu" signal "GND6")
		(32 "In15.Cu" signal "IN6")
		(34 "In16.Cu" signal "GND7")
		(2 "B.Cu" signal "BOTTOM")
		(9 "F.Adhes" user "F.Adhesive")
		(11 "B.Adhes" user "B.Adhesive")
		(13 "F.Paste" user "Package Geometry/Pastemask Top")
		(15 "B.Paste" user "Package Geometry/Pastemask Bottom")
		(5 "F.SilkS" user "Ref Des/Silkscreen Top")
		(7 "B.SilkS" user "Ref Des/Silkscreen Bottom")
		(1 "F.Mask" user "Board Geometry/Soldermask Top")
		(3 "B.Mask" user "Board Geometry/Soldermask Bottom")
		(17 "Dwgs.User" user "User.Drawings")
		(19 "Cmts.User" user "User.Comments")
		(21 "Eco1.User" user "User.Eco1")
		(23 "Eco2.User" user "User.Eco2")
		(25 "Edge.Cuts" user "Board Geometry/Outline")
		(27 "Margin" user)
		(31 "F.CrtYd" user "Package Geometry/Place Bound Top")
		(29 "B.CrtYd" user "Package Geometry/Place Bound Bottom")
		(35 "F.Fab" user "Ref Des/Assembly Top")
		(33 "B.Fab" user "Ref Des/Assembly Bottom")
	)
	(footprint ""
		(layer "F.Cu")
		(at 116.13388 -403.35073 90)
		(property "Reference" "R2835"
			(at 0 0 90)
			(layer "F.SilkS")
			(hide yes)
			(effects
				(font
					(size 1.27 1.27)
				)
			)
		)
		(property "Value" ""
			(at 0 0 90)
			(layer "F.Fab")
			(effects
				(font
					(size 1.27 1.27)
				)
			)
		)
		(duplicate_pad_numbers_are_jumpers no)
		(fp_line
			(start 0.7874 -0.4064)
			(end 0.7874 0.4064)
			(stroke
				(width 0.1524)
				(type default)
			)
			(layer "F.SilkS")
		)
		(fp_line
			(start -0.7874 -0.4064)
			(end 0.7874 -0.4064)
			(stroke
				(width 0.1524)
				(type default)
			)
			(layer "F.SilkS")
		)
		(fp_line
			(start 0.7874 0.4064)
			(end -0.7874 0.4064)
			(stroke
				(width 0.1524)
				(type default)
			)
			(layer "F.SilkS")
		)
		(fp_line
			(start -0.7874 0.4064)
			(end -0.7874 -0.4064)
			(stroke
				(width 0.1524)
				(type default)
			)
			(layer "F.SilkS")
		)
		(fp_line
			(start -0.12065 -0.305054)
			(end -0.12065 -0.2794)
			(stroke
				(width 0.1)
				(type default)
			)
			(layer "F.Fab")
		)
		(fp_line
			(start -0.67945 -0.305054)
			(end -0.12065 -0.305054)
			(stroke
				(width 0.1)
				(type default)
			)
			(layer "F.Fab")
		)
		(fp_line
			(start 0.67945 -0.3048)
			(end 0.67945 0.3048)
			(stroke
				(width 0.1)
				(type default)
			)
			(layer "F.Fab")
		)
		(fp_line
			(start 0.12065 -0.3048)
			(end 0.67945 -0.3048)
			(stroke
				(width 0.1)
				(type default)
			)
			(layer "F.Fab")
		)
		(fp_line
			(start 0.12065 -0.2794)
			(end 0.12065 -0.3048)
			(stroke
				(width 0.1)
				(type default)
			)
			(layer "F.Fab")
		)
		(fp_line
			(start -0.12065 -0.2794)
			(end 0.12065 -0.2794)
			(stroke
				(width 0.1)
				(type default)
			)
			(layer "F.Fab")
		)
		(fp_line
			(start 0.120396 0.2794)
			(end -0.12065 0.2794)
			(stroke
				(width 0.1)
				(type default)
			)
			(layer "F.Fab")
		)
		(fp_line
			(start -0.12065 0.2794)
			(end -0.12065 0.3048)
			(stroke
				(width 0.1)
				(type default)
			)
			(layer "F.Fab")
		)
		(fp_line
			(start 0.67945 0.3048)
			(end 0.120396 0.3048)
			(stroke
				(width 0.1)
				(type default)
			)
			(layer "F.Fab")
		)
		(fp_line
			(start 0.120396 0.3048)
			(end 0.120396 0.2794)
			(stroke
				(width 0.1)
				(type default)
			)
			(layer "F.Fab")
		)
		(fp_line
			(start -0.12065 0.3048)
			(end -0.67945 0.3048)
			(stroke
				(width 0.1)
				(type default)
			)
			(layer "F.Fab")
		)
		(fp_line
			(start -0.67945 0.3048)
			(end -0.67945 -0.305054)
			(stroke
				(width 0.1)
				(type default)
			)
			(layer "F.Fab")
		)
		(pad "1" smd circle
			(at -0.40005 0 90)
			(size 0 0)
			(layers "F.Cu" "F.Mask" "F.Paste")
			(net "P3V3_AUX")
		)
		(pad "2" smd circle
			(at 0.40005 0 90)
			(size 0 0)
			(layers "F.Cu" "F.Mask" "F.Paste")
			(net "BIC_MONITER_N")
		)
	)
	(footprint ""
		(layer "F.Cu")
		(at 169.44848 -425.922948 180)
		(property "Reference" "R2915"
			(at 0 0 180)
			(layer "F.SilkS")
			(hide yes)
			(effects
				(font
					(size 1.27 1.27)
				)
			)
		)
		(property "Value" ""
			(at 0 0 180)
			(layer "F.Fab")
			(effects
				(font
					(size 1.27 1.27)
				)
			)
		)
		(duplicate_pad_numbers_are_jumpers no)
		(fp_line
			(start 0.7874 0.4064)
			(end -0.7874 0.4064)
			(stroke
				(width 0.1524)
				(type default)
			)
			(layer "F.SilkS")
		)
		(fp_line
			(start 0.7874 -0.4064)
			(end 0.7874 0.4064)
			(stroke
				(width 0.1524)
				(type default)
			)
			(layer "F.SilkS")
		)
		(fp_line
			(start -0.7874 0.4064)
			(end -0.7874 -0.4064)
			(stroke
				(width 0.1524)
				(type default)
			)
			(layer "F.SilkS")
		)
		(fp_line
			(start -0.7874 -0.4064)
			(end 0.7874 -0.4064)
			(stroke
				(width 0.1524)
				(type default)
			)
			(layer "F.SilkS")
		)
		(fp_line
			(start 0.67945 0.3048)
			(end 0.120396 0.3048)
			(stroke
				(width 0.1)
				(type default)
			)
			(layer "F.Fab")
		)
		(fp_line
			(start 0.67945 -0.3048)
			(end 0.67945 0.3048)
			(stroke
				(width 0.1)
				(type default)
			)
			(layer "F.Fab")
		)
		(fp_line
			(start 0.12065 -0.2794)
			(end 0.12065 -0.3048)
			(stroke
				(width 0.1)
				(type default)
			)
			(layer "F.Fab")
		)
		(fp_line
			(start 0.12065 -0.3048)
			(end 0.67945 -0.3048)
			(stroke
				(width 0.1)
				(type default)
			)
			(layer "F.Fab")
		)
		(fp_line
			(start 0.120396 0.3048)
			(end 0.120396 0.2794)
			(stroke
				(width 0.1)
				(type default)
			)
			(layer "F.Fab")
		)
		(fp_line
			(start 0.120396 0.2794)
			(end -0.12065 0.2794)
			(stroke
				(width 0.1)
				(type default)
			)
			(layer "F.Fab")
		)
		(fp_line
			(start -0.12065 0.3048)
			(end -0.67945 0.3048)
			(stroke
				(width 0.1)
				(type default)
			)
			(layer "F.Fab")
		)
		(fp_line
			(start -0.12065 0.2794)
			(end -0.12065 0.3048)
			(stroke
				(width 0.1)
				(type default)
			)
			(layer "F.Fab")
		)
		(fp_line
			(start -0.12065 -0.2794)
			(end 0.12065 -0.2794)
			(stroke
				(width 0.1)
				(type default)
			)
			(layer "F.Fab")
		)
		(fp_line
			(start -0.12065 -0.305054)
			(end -0.12065 -0.2794)
			(stroke
				(width 0.1)
				(type default)
			)
			(layer "F.Fab")
		)
		(fp_line
			(start -0.67945 0.3048)
			(end -0.67945 -0.305054)
			(stroke
				(width 0.1)
				(type default)
			)
			(layer "F.Fab")
		)
		(fp_line
			(start -0.67945 -0.305054)
			(end -0.12065 -0.305054)
			(stroke
				(width 0.1)
				(type default)
			)
			(layer "F.Fab")
		)
		(pad "1" smd circle
			(at -0.40005 0 180)
			(size 0 0)
			(layers "F.Cu" "F.Mask" "F.Paste")
			(net "BMC_MONITER_R")
		)
		(pad "2" smd circle
			(at 0.40005 0 180)
			(size 0 0)
			(layers "F.Cu" "F.Mask" "F.Paste")
			(net "GND")
		)
	)
)
